(kicad_pcb
	(version 20241229)
	(generator "pcbnew")
	(generator_version "9.0")
	(general
		(thickness 1.258)
		(legacy_teardrops no)
	)
	(paper "A4")
	(title_block
		(date "2024-05-27")
		(rev "1.1.2")
		(comment 9 "footprint 28 of 64 (J1), pads 1-100 of 262")
	)
	(layers
		(0 "F.Cu" signal)
		(4 "In1.Cu" power)
		(6 "In2.Cu" power)
		(8 "In3.Cu" signal)
		(10 "In4.Cu" signal)
		(2 "B.Cu" signal)
		(9 "F.Adhes" user "F.Adhesive")
		(11 "B.Adhes" user "B.Adhesive")
		(13 "F.Paste" user)
		(15 "B.Paste" user)
		(5 "F.SilkS" user "F.Silkscreen")
		(7 "B.SilkS" user "B.Silkscreen")
		(1 "F.Mask" user)
		(3 "B.Mask" user)
		(17 "Dwgs.User" user "User.Drawings")
		(19 "Cmts.User" user "User.Comments")
		(21 "Eco1.User" user "User.Eco1")
		(23 "Eco2.User" user "User.Eco2")
		(25 "Edge.Cuts" user)
		(27 "Margin" user)
		(31 "F.CrtYd" user "F.Courtyard")
		(29 "B.CrtYd" user "B.Courtyard")
		(35 "F.Fab" user)
		(33 "B.Fab" user)
	)
	(footprint "antmicro-footprints:PCB-Edge_SODIMM_2x130_DDR4"
		(locked yes)
		(layer "F.Cu")
		(at 100 100)
		(property "Reference" "J1"
			(at 0 -4.2 0)
			(layer "F.SilkS")
			(hide yes)
			(effects
				(font
					(size 0.7 0.7)
					(thickness 0.15)
				)
				(justify left bottom)
			)
		)
		(property "Value" "PCB-Edge_SODIMM_2x130_DDR4"
			(at 0 1 0)
			(layer "F.Fab")
			(effects
				(font
					(size 0.7 0.7)
					(thickness 0.15)
				)
				(justify left bottom)
			)
		)
		(property "Description" "DDR SO-DIMM PCB Edge"
			(at 0 0 0)
			(layer "F.Fab")
			(hide yes)
			(effects
				(font
					(size 1.27 1.27)
					(thickness 0.15)
				)
			)
		)
		(property "Author" "Antmicro"
			(at 0 0 0)
			(layer "F.Fab")
			(hide yes)
			(effects
				(font
					(size 1 1)
					(thickness 0.15)
				)
			)
		)
		(property "License" "Apache-2.0"
			(at 0 0 0)
			(layer "F.Fab")
			(hide yes)
			(effects
				(font
					(size 1 1)
					(thickness 0.15)
				)
			)
		)
		(property "MPN" ""
			(at 0 0 0)
			(layer "F.Fab")
			(hide yes)
			(effects
				(font
					(size 1 1)
					(thickness 0.15)
				)
			)
		)
		(property "Manufacturer" ""
			(at 0 0 0)
			(layer "F.Fab")
			(hide yes)
			(effects
				(font
					(size 1 1)
					(thickness 0.15)
				)
			)
		)
		(property "Public" "False"
			(at 0 0 0)
			(layer "F.Fab")
			(hide yes)
			(effects
				(font
					(size 1 1)
					(thickness 0.15)
				)
			)
		)
		(sheetname "SODIMM")
		(sheetfile "sodim.kicad_sch")
		(attr exclude_from_pos_files exclude_from_bom)
		(pad "" np_thru_hole circle
			(at 1.999 -6)
			(size 1.8 1.8)
			(drill 1.8)
			(layers "*.Cu" "*.Mask")
		)
		(pad "" np_thru_hole circle
			(at 67.599 -6)
			(size 1.8 1.8)
			(drill 1.8)
			(layers "*.Cu" "*.Mask")
		)
		(pad "1" smd rect
			(at 1.425 -1.301)
			(size 0.35 2.5)
			(layers "F.Cu" "F.Mask")
			(net 1 "GND")
			(pinfunction "1")
			(pintype "passive")
		)
		(pad "2" smd rect
			(at 1.675 -1.301)
			(size 0.35 2.5)
			(layers "B.Cu" "B.Mask")
			(net 1 "GND")
			(pinfunction "2")
			(pintype "passive")
		)
		(pad "3" smd rect
			(at 1.925 -1.301)
			(size 0.35 2.5)
			(layers "F.Cu" "F.Mask")
			(net 1 "GND")
			(pinfunction "3")
			(pintype "passive")
		)
		(pad "4" smd rect
			(at 2.173 -1.301)
			(size 0.35 2.5)
			(layers "B.Cu" "B.Mask")
			(net 1 "GND")
			(pinfunction "4")
			(pintype "passive")
		)
		(pad "5" smd rect
			(at 2.423 -1.301)
			(size 0.35 2.5)
			(layers "F.Cu" "F.Mask")
			(net 1 "GND")
			(pinfunction "5")
			(pintype "passive")
		)
		(pad "6" smd rect
			(at 2.673 -1.301)
			(size 0.35 2.5)
			(layers "B.Cu" "B.Mask")
			(net 1 "GND")
			(pinfunction "6")
			(pintype "passive")
		)
		(pad "7" smd rect
			(at 2.923 -1.301)
			(size 0.35 2.5)
			(layers "F.Cu" "F.Mask")
			(net 1 "GND")
			(pinfunction "7")
			(pintype "passive")
		)
		(pad "8" smd rect
			(at 3.173 -1.301)
			(size 0.35 2.5)
			(layers "B.Cu" "B.Mask")
			(net 1 "GND")
			(pinfunction "8")
			(pintype "passive")
		)
		(pad "9" smd rect
			(at 3.423 -1.301)
			(size 0.35 2.5)
			(layers "F.Cu" "F.Mask")
			(net 1 "GND")
			(pinfunction "9")
			(pintype "passive")
		)
		(pad "10" smd rect
			(at 3.673 -1.301)
			(size 0.35 2.5)
			(layers "B.Cu" "B.Mask")
			(net 1 "GND")
			(pinfunction "10")
			(pintype "passive")
		)
		(pad "11" smd rect
			(at 3.923 -1.301)
			(size 0.35 2.5)
			(layers "F.Cu" "F.Mask")
			(net 1 "GND")
			(pinfunction "11")
			(pintype "passive")
		)
		(pad "12" smd rect
			(at 4.174 -1.301)
			(size 0.35 2.5)
			(layers "B.Cu" "B.Mask")
			(net 1 "GND")
			(pinfunction "12")
			(pintype "passive")
		)
		(pad "13" smd rect
			(at 4.424 -1.301)
			(size 0.35 2.5)
			(layers "F.Cu" "F.Mask")
			(net 1 "GND")
			(pinfunction "13")
			(pintype "passive")
		)
		(pad "14" smd rect
			(at 4.674 -1.301)
			(size 0.35 2.5)
			(layers "B.Cu" "B.Mask")
			(net 1 "GND")
			(pinfunction "14")
			(pintype "passive")
		)
		(pad "15" smd rect
			(at 4.924 -1.301)
			(size 0.35 2.5)
			(layers "F.Cu" "F.Mask")
			(net 1 "GND")
			(pinfunction "15")
			(pintype "passive")
		)
		(pad "16" smd rect
			(at 5.174 -1.301)
			(size 0.35 2.5)
			(layers "B.Cu" "B.Mask")
			(net 1 "GND")
			(pinfunction "16")
			(pintype "passive")
		)
		(pad "17" smd rect
			(at 5.424 -1.301)
			(size 0.35 2.5)
			(layers "F.Cu" "F.Mask")
			(net 1 "GND")
			(pinfunction "17")
			(pintype "passive")
		)
		(pad "18" smd rect
			(at 5.674 -1.301)
			(size 0.35 2.5)
			(layers "B.Cu" "B.Mask")
			(net 1 "GND")
			(pinfunction "18")
			(pintype "passive")
		)
		(pad "19" smd rect
			(at 5.924 -1.301)
			(size 0.35 2.5)
			(layers "F.Cu" "F.Mask")
			(net 1 "GND")
			(pinfunction "19")
			(pintype "passive")
		)
		(pad "20" smd rect
			(at 6.174 -1.301)
			(size 0.35 2.5)
			(layers "B.Cu" "B.Mask")
			(net 1 "GND")
			(pinfunction "20")
			(pintype "passive")
		)
		(pad "21" smd rect
			(at 6.424 -1.301)
			(size 0.35 2.5)
			(layers "F.Cu" "F.Mask")
			(net 1 "GND")
			(pinfunction "21")
			(pintype "passive")
		)
		(pad "22" smd rect
			(at 6.674 -1.301)
			(size 0.35 2.5)
			(layers "B.Cu" "B.Mask")
			(net 1 "GND")
			(pinfunction "22")
			(pintype "passive")
		)
		(pad "23" smd rect
			(at 6.924 -1.301)
			(size 0.35 2.5)
			(layers "F.Cu" "F.Mask")
			(net 1 "GND")
			(pinfunction "23")
			(pintype "passive")
		)
		(pad "24" smd rect
			(at 7.174 -1.301)
			(size 0.35 2.5)
			(layers "B.Cu" "B.Mask")
			(net 1 "GND")
			(pinfunction "24")
			(pintype "passive")
		)
		(pad "25" smd rect
			(at 7.424 -1.301)
			(size 0.35 2.5)
			(layers "F.Cu" "F.Mask")
			(net 1 "GND")
			(pinfunction "25")
			(pintype "passive")
		)
		(pad "26" smd rect
			(at 7.674 -1.301)
			(size 0.35 2.5)
			(layers "B.Cu" "B.Mask")
			(net 1 "GND")
			(pinfunction "26")
			(pintype "passive")
		)
		(pad "27" smd rect
			(at 7.924 -1.301)
			(size 0.35 2.5)
			(layers "F.Cu" "F.Mask")
			(net 1 "GND")
			(pinfunction "27")
			(pintype "passive")
		)
		(pad "28" smd rect
			(at 8.175 -1.301)
			(size 0.35 2.5)
			(layers "B.Cu" "B.Mask")
			(net 1 "GND")
			(pinfunction "28")
			(pintype "passive")
		)
		(pad "29" smd rect
			(at 8.425 -1.301)
			(size 0.35 2.5)
			(layers "F.Cu" "F.Mask")
			(net 1 "GND")
			(pinfunction "29")
			(pintype "passive")
		)
		(pad "30" smd rect
			(at 8.675 -1.301)
			(size 0.35 2.5)
			(layers "B.Cu" "B.Mask")
			(net 1 "GND")
			(pinfunction "30")
			(pintype "passive")
		)
		(pad "31" smd rect
			(at 8.925 -1.301)
			(size 0.35 2.5)
			(layers "F.Cu" "F.Mask")
			(net 1 "GND")
			(pinfunction "31")
			(pintype "passive")
		)
		(pad "32" smd rect
			(at 9.175 -1.301)
			(size 0.35 2.5)
			(layers "B.Cu" "B.Mask")
			(net 1 "GND")
			(pinfunction "32")
			(pintype "passive")
		)
		(pad "33" smd rect
			(at 9.425 -1.301)
			(size 0.35 2.5)
			(layers "F.Cu" "F.Mask")
			(net 1 "GND")
			(pinfunction "33")
			(pintype "passive")
		)
		(pad "34" smd rect
			(at 9.675 -1.301)
			(size 0.35 2.5)
			(layers "B.Cu" "B.Mask")
			(net 1 "GND")
			(pinfunction "34")
			(pintype "passive")
		)
		(pad "35" smd rect
			(at 9.925 -1.301)
			(size 0.35 2.5)
			(layers "F.Cu" "F.Mask")
			(net 1 "GND")
			(pinfunction "35")
			(pintype "passive")
		)
		(pad "36" smd rect
			(at 10.175 -1.301)
			(size 0.35 2.5)
			(layers "B.Cu" "B.Mask")
			(net 1 "GND")
			(pinfunction "36")
			(pintype "passive")
		)
		(pad "37" smd rect
			(at 10.425 -1.301)
			(size 0.35 2.5)
			(layers "F.Cu" "F.Mask")
			(net 1 "GND")
			(pinfunction "37")
			(pintype "passive")
		)
		(pad "38" smd rect
			(at 10.675 -1.301)
			(size 0.35 2.5)
			(layers "B.Cu" "B.Mask")
			(net 1 "GND")
			(pinfunction "38")
			(pintype "passive")
		)
		(pad "39" smd rect
			(at 10.925 -1.301)
			(size 0.35 2.5)
			(layers "F.Cu" "F.Mask")
			(net 1 "GND")
			(pinfunction "39")
			(pintype "passive")
		)
		(pad "40" smd rect
			(at 11.175 -1.301)
			(size 0.35 2.5)
			(layers "B.Cu" "B.Mask")
			(net 1 "GND")
			(pinfunction "40")
			(pintype "passive")
		)
		(pad "41" smd rect
			(at 11.425 -1.301)
			(size 0.35 2.5)
			(layers "F.Cu" "F.Mask")
			(net 1 "GND")
			(pinfunction "41")
			(pintype "passive")
		)
		(pad "42" smd rect
			(at 11.675 -1.301)
			(size 0.35 2.5)
			(layers "B.Cu" "B.Mask")
			(net 1 "GND")
			(pinfunction "42")
			(pintype "passive")
		)
		(pad "43" smd rect
			(at 11.925 -1.301)
			(size 0.35 2.5)
			(layers "F.Cu" "F.Mask")
			(net 1 "GND")
			(pinfunction "43")
			(pintype "passive")
		)
		(pad "44" smd rect
			(at 12.175 -1.301)
			(size 0.35 2.5)
			(layers "B.Cu" "B.Mask")
			(net 1 "GND")
			(pinfunction "44")
			(pintype "passive")
		)
		(pad "45" smd rect
			(at 12.425 -1.301)
			(size 0.35 2.5)
			(layers "F.Cu" "F.Mask")
			(net 1 "GND")
			(pinfunction "45")
			(pintype "passive")
		)
		(pad "46" smd rect
			(at 12.675 -1.301)
			(size 0.35 2.5)
			(layers "B.Cu" "B.Mask")
			(net 1 "GND")
			(pinfunction "46")
			(pintype "passive")
		)
		(pad "47" smd rect
			(at 12.925 -1.301)
			(size 0.35 2.5)
			(layers "F.Cu" "F.Mask")
			(net 1 "GND")
			(pinfunction "47")
			(pintype "passive")
		)
		(pad "48" smd rect
			(at 13.175 -1.301)
			(size 0.35 2.5)
			(layers "B.Cu" "B.Mask")
			(net 1 "GND")
			(pinfunction "48")
			(pintype "passive")
		)
		(pad "49" smd rect
			(at 13.425 -1.301)
			(size 0.35 2.5)
			(layers "F.Cu" "F.Mask")
			(net 1 "GND")
			(pinfunction "49")
			(pintype "passive")
		)
		(pad "50" smd rect
			(at 13.675 -1.301)
			(size 0.35 2.5)
			(layers "B.Cu" "B.Mask")
			(net 1 "GND")
			(pinfunction "50")
			(pintype "passive")
		)
		(pad "51" smd rect
			(at 13.925 -1.301)
			(size 0.35 2.5)
			(layers "F.Cu" "F.Mask")
			(net 70 "unconnected-(J1-Pad51)")
			(pinfunction "51")
			(pintype "passive+no_connect")
		)
		(pad "52" smd rect
			(at 14.175 -1.301)
			(size 0.35 2.5)
			(layers "B.Cu" "B.Mask")
			(net 71 "unconnected-(J1-Pad52)")
			(pinfunction "52")
			(pintype "passive+no_connect")
		)
		(pad "53" smd rect
			(at 14.425 -1.301)
			(size 0.35 2.5)
			(layers "F.Cu" "F.Mask")
			(net 72 "unconnected-(J1-Pad53)")
			(pinfunction "53")
			(pintype "passive+no_connect")
		)
		(pad "54" smd rect
			(at 14.675 -1.301)
			(size 0.35 2.5)
			(layers "B.Cu" "B.Mask")
			(net 73 "unconnected-(J1-Pad54)")
			(pinfunction "54")
			(pintype "passive+no_connect")
		)
		(pad "55" smd rect
			(at 14.925 -1.301)
			(size 0.35 2.5)
			(layers "F.Cu" "F.Mask")
			(net 74 "unconnected-(J1-Pad55)")
			(pinfunction "55")
			(pintype "passive+no_connect")
		)
		(pad "56" smd rect
			(at 15.175 -1.301)
			(size 0.35 2.5)
			(layers "B.Cu" "B.Mask")
			(net 75 "unconnected-(J1-Pad56)")
			(pinfunction "56")
			(pintype "passive+no_connect")
		)
		(pad "57" smd rect
			(at 15.425 -1.301)
			(size 0.35 2.5)
			(layers "F.Cu" "F.Mask")
			(net 76 "unconnected-(J1-Pad57)")
			(pinfunction "57")
			(pintype "passive+no_connect")
		)
		(pad "58" smd rect
			(at 15.675 -1.301)
			(size 0.35 2.5)
			(layers "B.Cu" "B.Mask")
			(net 77 "unconnected-(J1-Pad58)")
			(pinfunction "58")
			(pintype "passive+no_connect")
		)
		(pad "59" smd rect
			(at 15.925 -1.301)
			(size 0.35 2.5)
			(layers "F.Cu" "F.Mask")
			(net 78 "unconnected-(J1-Pad59)")
			(pinfunction "59")
			(pintype "passive+no_connect")
		)
		(pad "60" smd rect
			(at 16.175 -1.301)
			(size 0.35 2.5)
			(layers "B.Cu" "B.Mask")
			(net 79 "unconnected-(J1-Pad60)")
			(pinfunction "60")
			(pintype "passive+no_connect")
		)
		(pad "61" smd rect
			(at 16.425 -1.301)
			(size 0.35 2.5)
			(layers "F.Cu" "F.Mask")
			(net 80 "unconnected-(J1-Pad61)")
			(pinfunction "61")
			(pintype "passive+no_connect")
		)
		(pad "62" smd rect
			(at 16.675 -1.301)
			(size 0.35 2.5)
			(layers "B.Cu" "B.Mask")
			(net 81 "unconnected-(J1-Pad62)")
			(pinfunction "62")
			(pintype "passive+no_connect")
		)
		(pad "63" smd rect
			(at 16.925 -1.301)
			(size 0.35 2.5)
			(layers "F.Cu" "F.Mask")
			(net 82 "unconnected-(J1-Pad63)")
			(pinfunction "63")
			(pintype "passive+no_connect")
		)
		(pad "64" smd rect
			(at 17.175 -1.301)
			(size 0.35 2.5)
			(layers "B.Cu" "B.Mask")
			(net 83 "unconnected-(J1-Pad64)")
			(pinfunction "64")
			(pintype "passive+no_connect")
		)
		(pad "65" smd rect
			(at 17.425 -1.301)
			(size 0.35 2.5)
			(layers "F.Cu" "F.Mask")
			(net 84 "unconnected-(J1-Pad65)")
			(pinfunction "65")
			(pintype "passive+no_connect")
		)
		(pad "66" smd rect
			(at 17.675 -1.301)
			(size 0.35 2.5)
			(layers "B.Cu" "B.Mask")
			(net 85 "unconnected-(J1-Pad66)")
			(pinfunction "66")
			(pintype "passive+no_connect")
		)
		(pad "67" smd rect
			(at 17.925 -1.301)
			(size 0.35 2.5)
			(layers "F.Cu" "F.Mask")
			(net 86 "unconnected-(J1-Pad67)")
			(pinfunction "67")
			(pintype "passive+no_connect")
		)
		(pad "68" smd rect
			(at 18.175 -1.301)
			(size 0.35 2.5)
			(layers "B.Cu" "B.Mask")
			(net 87 "unconnected-(J1-Pad68)")
			(pinfunction "68")
			(pintype "passive+no_connect")
		)
		(pad "69" smd rect
			(at 18.425 -1.301)
			(size 0.35 2.5)
			(layers "F.Cu" "F.Mask")
			(net 88 "unconnected-(J1-Pad69)")
			(pinfunction "69")
			(pintype "passive+no_connect")
		)
		(pad "70" smd rect
			(at 18.675 -1.301)
			(size 0.35 2.5)
			(layers "B.Cu" "B.Mask")
			(net 89 "unconnected-(J1-Pad70)")
			(pinfunction "70")
			(pintype "passive+no_connect")
		)
		(pad "71" smd rect
			(at 18.925 -1.301)
			(size 0.35 2.5)
			(layers "F.Cu" "F.Mask")
			(net 90 "unconnected-(J1-Pad71)")
			(pinfunction "71")
			(pintype "passive+no_connect")
		)
		(pad "72" smd rect
			(at 19.175 -1.301)
			(size 0.35 2.5)
			(layers "B.Cu" "B.Mask")
			(net 91 "unconnected-(J1-Pad72)")
			(pinfunction "72")
			(pintype "passive+no_connect")
		)
		(pad "73" smd rect
			(at 19.425 -1.301)
			(size 0.35 2.5)
			(layers "F.Cu" "F.Mask")
			(net 92 "unconnected-(J1-Pad73)")
			(pinfunction "73")
			(pintype "passive+no_connect")
		)
		(pad "74" smd rect
			(at 19.675 -1.301)
			(size 0.35 2.5)
			(layers "B.Cu" "B.Mask")
			(net 93 "unconnected-(J1-Pad74)")
			(pinfunction "74")
			(pintype "passive+no_connect")
		)
		(pad "75" smd rect
			(at 19.925 -1.301)
			(size 0.35 2.5)
			(layers "F.Cu" "F.Mask")
			(net 94 "unconnected-(J1-Pad75)")
			(pinfunction "75")
			(pintype "passive+no_connect")
		)
		(pad "76" smd rect
			(at 20.175 -1.301)
			(size 0.35 2.5)
			(layers "B.Cu" "B.Mask")
			(net 95 "unconnected-(J1-Pad76)")
			(pinfunction "76")
			(pintype "passive+no_connect")
		)
		(pad "77" smd rect
			(at 20.425 -1.301)
			(size 0.35 2.5)
			(layers "F.Cu" "F.Mask")
			(net 96 "unconnected-(J1-Pad77)")
			(pinfunction "77")
			(pintype "passive+no_connect")
		)
		(pad "78" smd rect
			(at 20.675 -1.301)
			(size 0.35 2.5)
			(layers "B.Cu" "B.Mask")
			(net 97 "unconnected-(J1-Pad78)")
			(pinfunction "78")
			(pintype "passive+no_connect")
		)
		(pad "79" smd rect
			(at 20.925 -1.301)
			(size 0.35 2.5)
			(layers "F.Cu" "F.Mask")
			(net 98 "unconnected-(J1-Pad79)")
			(pinfunction "79")
			(pintype "passive+no_connect")
		)
		(pad "80" smd rect
			(at 21.175 -1.301)
			(size 0.35 2.5)
			(layers "B.Cu" "B.Mask")
			(net 99 "unconnected-(J1-Pad80)")
			(pinfunction "80")
			(pintype "passive+no_connect")
		)
		(pad "81" smd rect
			(at 21.425 -1.301)
			(size 0.35 2.5)
			(layers "F.Cu" "F.Mask")
			(net 100 "unconnected-(J1-Pad81)")
			(pinfunction "81")
			(pintype "passive+no_connect")
		)
		(pad "82" smd rect
			(at 21.675 -1.301)
			(size 0.35 2.5)
			(layers "B.Cu" "B.Mask")
			(net 101 "unconnected-(J1-Pad82)")
			(pinfunction "82")
			(pintype "passive+no_connect")
		)
		(pad "83" smd rect
			(at 21.925 -1.301)
			(size 0.35 2.5)
			(layers "F.Cu" "F.Mask")
			(net 102 "unconnected-(J1-Pad83)")
			(pinfunction "83")
			(pintype "passive+no_connect")
		)
		(pad "84" smd rect
			(at 22.175 -1.301)
			(size 0.35 2.5)
			(layers "B.Cu" "B.Mask")
			(net 103 "unconnected-(J1-Pad84)")
			(pinfunction "84")
			(pintype "passive+no_connect")
		)
		(pad "85" smd rect
			(at 22.425 -1.301)
			(size 0.35 2.5)
			(layers "F.Cu" "F.Mask")
			(net 104 "unconnected-(J1-Pad85)")
			(pinfunction "85")
			(pintype "passive+no_connect")
		)
		(pad "86" smd rect
			(at 22.675 -1.301)
			(size 0.35 2.5)
			(layers "B.Cu" "B.Mask")
			(net 105 "unconnected-(J1-Pad86)")
			(pinfunction "86")
			(pintype "passive+no_connect")
		)
		(pad "87" smd rect
			(at 22.925 -1.301)
			(size 0.35 2.5)
			(layers "F.Cu" "F.Mask")
			(net 106 "unconnected-(J1-Pad87)")
			(pinfunction "87")
			(pintype "passive+no_connect")
		)
		(pad "88" smd rect
			(at 23.175 -1.301)
			(size 0.35 2.5)
			(layers "B.Cu" "B.Mask")
			(net 107 "unconnected-(J1-Pad88)")
			(pinfunction "88")
			(pintype "passive+no_connect")
		)
		(pad "89" smd rect
			(at 23.425 -1.301)
			(size 0.35 2.5)
			(layers "F.Cu" "F.Mask")
			(net 108 "unconnected-(J1-Pad89)")
			(pinfunction "89")
			(pintype "passive+no_connect")
		)
		(pad "90" smd rect
			(at 23.675 -1.301)
			(size 0.35 2.5)
			(layers "B.Cu" "B.Mask")
			(net 109 "unconnected-(J1-Pad90)")
			(pinfunction "90")
			(pintype "passive+no_connect")
		)
		(pad "91" smd rect
			(at 23.925 -1.301)
			(size 0.35 2.5)
			(layers "F.Cu" "F.Mask")
			(net 110 "unconnected-(J1-Pad91)")
			(pinfunction "91")
			(pintype "passive+no_connect")
		)
		(pad "92" smd rect
			(at 24.175 -1.301)
			(size 0.35 2.5)
			(layers "B.Cu" "B.Mask")
			(net 111 "unconnected-(J1-Pad92)")
			(pinfunction "92")
			(pintype "passive+no_connect")
		)
		(pad "93" smd rect
			(at 24.425 -1.301)
			(size 0.35 2.5)
			(layers "F.Cu" "F.Mask")
			(net 51 "1V1_SYS")
			(pinfunction "93")
			(pintype "passive")
		)
		(pad "94" smd rect
			(at 24.675 -1.301)
			(size 0.35 2.5)
			(layers "B.Cu" "B.Mask")
			(net 112 "unconnected-(J1-Pad94)")
			(pinfunction "94")
			(pintype "passive+no_connect")
		)
		(pad "95" smd rect
			(at 24.925 -1.301)
			(size 0.35 2.5)
			(layers "F.Cu" "F.Mask")
			(net 51 "1V1_SYS")
			(pinfunction "95")
			(pintype "passive")
		)
		(pad "96" smd rect
			(at 25.175 -1.301)
			(size 0.35 2.5)
			(layers "B.Cu" "B.Mask")
			(net 113 "unconnected-(J1-Pad96)")
			(pinfunction "96")
			(pintype "passive+no_connect")
		)
		(pad "97" smd rect
			(at 25.425 -1.301)
			(size 0.35 2.5)
			(layers "F.Cu" "F.Mask")
			(net 51 "1V1_SYS")
			(pinfunction "97")
			(pintype "passive")
		)
		(pad "98" smd rect
			(at 25.675 -1.301)
			(size 0.35 2.5)
			(layers "B.Cu" "B.Mask")
			(net 114 "unconnected-(J1-Pad98)")
			(pinfunction "98")
			(pintype "passive+no_connect")
		)
	)
)
